(kicad_pcb
	(version 20241229)
	(generator "pcbnew")
	(generator_version "9.0")
	(general
		(thickness 1.61)
		(legacy_teardrops no)
	)
	(paper "A3")
	(title_block
		(title "RDIMM DDR5 Tester")
		(date "2026-05-21")
		(rev "2.2.0")
		(company "Antmicro")
		(comment 9 "footprints 538-542 of 796")
	)
	(layers
		(0 "F.Cu" signal)
		(4 "In1.Cu" power)
		(6 "In2.Cu" mixed)
		(8 "In3.Cu" power)
		(10 "In4.Cu" mixed)
		(12 "In5.Cu" power)
		(14 "In6.Cu" mixed)
		(16 "In7.Cu" power)
		(18 "In8.Cu" power)
		(20 "In9.Cu" mixed)
		(22 "In10.Cu" power)
		(2 "B.Cu" signal)
		(9 "F.Adhes" user "F.Adhesive")
		(11 "B.Adhes" user "B.Adhesive")
		(13 "F.Paste" user)
		(15 "B.Paste" user)
		(5 "F.SilkS" user "F.Silkscreen")
		(7 "B.SilkS" user "B.Silkscreen")
		(1 "F.Mask" user)
		(3 "B.Mask" user)
		(17 "Dwgs.User" user "User.Drawings")
		(19 "Cmts.User" user "User.Comments")
		(21 "Eco1.User" user "User.Eco1")
		(23 "Eco2.User" user "User.Eco2")
		(25 "Edge.Cuts" user)
		(27 "Margin" user)
		(31 "F.CrtYd" user "F.Courtyard")
		(29 "B.CrtYd" user "B.Courtyard")
		(35 "F.Fab" user)
		(33 "B.Fab" user)
	)
	(footprint "antmicro-footprints:Coax_Conn_U.FL"
		(layer "B.Cu")
		(at 123.9 102.65 -90)
		(descr "https://media.digikey.com/pdf/Data%20Sheets/Hirose%20PDFs/UFL%20Series.pdf")
		(property "Reference" "J14"
			(at -2.16 2.19 90)
			(layer "B.SilkS")
			(hide yes)
			(effects
				(font
					(size 0.7 0.7)
					(thickness 0.15)
				)
				(justify left bottom mirror)
			)
		)
		(property "Value" "U_FL-R-SMT-1"
			(at -4.13 -2.52 90)
			(layer "B.Fab")
			(effects
				(font
					(size 0.7 0.7)
					(thickness 0.15)
				)
				(justify left bottom mirror)
			)
		)
		(property "Datasheet" "https://media.digikey.com/pdf/Data%20Sheets/Hirose%20PDFs/UFL%20Series.pdf"
			(at 0 0 270)
			(layer "F.Fab")
			(hide yes)
			(effects
				(font
					(size 1.27 1.27)
					(thickness 0.15)
				)
			)
		)
		(property "MPN" "U.FL-R-SMT-1(10)"
			(at 0 0 270)
			(unlocked yes)
			(layer "B.Fab")
			(hide yes)
			(effects
				(font
					(size 1 1)
					(thickness 0.15)
				)
				(justify mirror)
			)
		)
		(property "Manufacturer" "Hirose Electric"
			(at 0 0 270)
			(unlocked yes)
			(layer "B.Fab")
			(hide yes)
			(effects
				(font
					(size 1 1)
					(thickness 0.15)
				)
				(justify mirror)
			)
		)
		(property "Author" "Antmicro"
			(at 0 0 270)
			(unlocked yes)
			(layer "B.Fab")
			(hide yes)
			(effects
				(font
					(size 1 1)
					(thickness 0.15)
				)
				(justify mirror)
			)
		)
		(property "License" "Apache-2.0"
			(at 0 0 270)
			(unlocked yes)
			(layer "B.Fab")
			(hide yes)
			(effects
				(font
					(size 1 1)
					(thickness 0.15)
				)
				(justify mirror)
			)
		)
		(sheetname "/Debug FTDI + VNA/")
		(sheetfile "debug-ftdi.kicad_sch")
		(attr smd)
		(fp_line
			(start -1.613 1.651)
			(end -1.113 1.651)
			(stroke
				(width 0.15)
				(type solid)
			)
			(layer "B.SilkS")
		)
		(fp_line
			(start -1.613 1.651)
			(end -1.613 1.325)
			(stroke
				(width 0.15)
				(type solid)
			)
			(layer "B.SilkS")
		)
		(fp_line
			(start 1.588 1.651)
			(end 1.088 1.651)
			(stroke
				(width 0.15)
				(type solid)
			)
			(layer "B.SilkS")
		)
		(fp_line
			(start 1.588 1.651)
			(end 1.588 1.325)
			(stroke
				(width 0.15)
				(type solid)
			)
			(layer "B.SilkS")
		)
		(fp_line
			(start -1.613 -1.648)
			(end -1.613 -1.325)
			(stroke
				(width 0.15)
				(type solid)
			)
			(layer "B.SilkS")
		)
		(fp_line
			(start -1.613 -1.648)
			(end -1.113 -1.648)
			(stroke
				(width 0.15)
				(type solid)
			)
			(layer "B.SilkS")
		)
		(fp_line
			(start 1.588 -1.648)
			(end 1.588 -1.325)
			(stroke
				(width 0.15)
				(type solid)
			)
			(layer "B.SilkS")
		)
		(fp_line
			(start 1.588 -1.648)
			(end 1.088 -1.648)
			(stroke
				(width 0.15)
				(type solid)
			)
			(layer "B.SilkS")
		)
		(fp_rect
			(start -2 2.051)
			(end 1.999 -2.05)
			(stroke
				(width 0.05)
				(type solid)
			)
			(fill no)
			(layer "B.CrtYd")
		)
		(fp_line
			(start -1.512 1.551)
			(end 1.487 1.551)
			(stroke
				(width 0.15)
				(type solid)
			)
			(layer "B.Fab")
		)
		(fp_line
			(start -1.512 -1.55)
			(end -1.512 1.551)
			(stroke
				(width 0.15)
				(type solid)
			)
			(layer "B.Fab")
		)
		(fp_line
			(start -1.512 -1.55)
			(end 1.487 -1.55)
			(stroke
				(width 0.15)
				(type solid)
			)
			(layer "B.Fab")
		)
		(fp_line
			(start 1.487 -1.55)
			(end 1.487 1.551)
			(stroke
				(width 0.15)
				(type solid)
			)
			(layer "B.Fab")
		)
		(fp_text user "${REFERENCE}"
			(at -4.13 -6.92 90)
			(layer "B.Fab")
			(effects
				(font
					(size 0.7 0.7)
					(thickness 0.15)
				)
				(justify left bottom mirror)
			)
		)
		(fp_text user "License: Apache-2.0"
			(at -4.13 -5.72 90)
			(layer "B.Fab")
			(effects
				(font
					(size 0.7 0.7)
					(thickness 0.15)
				)
				(justify left bottom mirror)
			)
		)
		(fp_text user "Author: Antmicro"
			(at -4.13 -4.52 90)
			(layer "B.Fab")
			(effects
				(font
					(size 0.7 0.7)
					(thickness 0.15)
				)
				(justify left bottom mirror)
			)
		)
		(pad "1" smd rect
			(at -0.012 -1.499 270)
			(size 1 1.05)
			(layers "B.Cu" "B.Mask" "B.Paste")
			(net 370 "Net-(J14-Pad1)")
			(pintype "passive")
		)
		(pad "SH1" smd rect
			(at 1.463 0 270)
			(size 1.05 2.2)
			(layers "B.Cu" "B.Mask" "B.Paste")
			(net 1 "GND")
			(pintype "passive")
		)
		(pad "SH2" smd rect
			(at -1.488 0 270)
			(size 1.05 2.2)
			(layers "B.Cu" "B.Mask" "B.Paste")
			(net 1 "GND")
			(pintype "passive")
		)
		(zone
			(net 0)
			(net_name "")
			(layer "B.Cu")
			(hatch edge 0.508)
			(connect_pads
				(clearance 0)
			)
			(min_thickness 0.254)
			(filled_areas_thickness no)
			(keepout
				(tracks not_allowed)
				(vias not_allowed)
				(pads not_allowed)
				(copperpour not_allowed)
				(footprints not_allowed)
			)
			(placement
				(enabled no)
				(sheetname "")
			)
			(fill
				(thermal_gap 0.508)
				(thermal_bridge_width 0.508)
			)
			(polygon
				(pts
					(xy 124.86 103.58) (xy 124.86 101.7) (xy 122.8 101.7) (xy 122.8 103.58)
				)
			)
		)
	)
	(footprint "antmicro-footprints:R_0402_1005Metric"
		(layer "B.Cu")
		(at 215.1 185.235 90)
		(descr "Resistor SMD 0402")
		(tags "resistor SMD 0402")
		(property "Reference" "R188"
			(at -1.765 -0.6 90)
			(layer "B.SilkS")
			(effects
				(font
					(size 0.7 0.7)
					(thickness 0.15)
				)
				(justify right bottom mirror)
			)
		)
		(property "Value" "R_47k_0402"
			(at -1.011843 -1.772047 90)
			(layer "B.Fab")
			(effects
				(font
					(size 0.7 0.7)
					(thickness 0.15)
				)
				(justify right bottom mirror)
			)
		)
		(property "Datasheet" "https://www.bourns.com/docs/product-datasheets/cr.pdf"
			(at 0 0 90)
			(layer "F.Fab")
			(hide yes)
			(effects
				(font
					(size 1.27 1.27)
					(thickness 0.15)
				)
			)
		)
		(property "MPN" "CR0402-FX-4702GLF"
			(at 0 0 90)
			(unlocked yes)
			(layer "B.Fab")
			(hide yes)
			(effects
				(font
					(size 1 1)
					(thickness 0.15)
				)
				(justify mirror)
			)
		)
		(property "Manufacturer" "Bourns"
			(at 0 0 90)
			(unlocked yes)
			(layer "B.Fab")
			(hide yes)
			(effects
				(font
					(size 1 1)
					(thickness 0.15)
				)
				(justify mirror)
			)
		)
		(property "License" "Apache-2.0"
			(at 0 0 90)
			(unlocked yes)
			(layer "B.Fab")
			(hide yes)
			(effects
				(font
					(size 1 1)
					(thickness 0.15)
				)
				(justify mirror)
			)
		)
		(property "Author" "Antmicro"
			(at 0 0 90)
			(unlocked yes)
			(layer "B.Fab")
			(hide yes)
			(effects
				(font
					(size 1 1)
					(thickness 0.15)
				)
				(justify mirror)
			)
		)
		(property "Val" "47k"
			(at 0 0 90)
			(unlocked yes)
			(layer "B.Fab")
			(hide yes)
			(effects
				(font
					(size 1 1)
					(thickness 0.15)
				)
				(justify mirror)
			)
		)
		(property "Tolerance" "1%"
			(at 0 0 90)
			(unlocked yes)
			(layer "B.Fab")
			(hide yes)
			(effects
				(font
					(size 1 1)
					(thickness 0.15)
				)
				(justify mirror)
			)
		)
		(sheetname "/Supply/DC-DC VCCINT/")
		(sheetfile "dc-dc-vccint.kicad_sch")
		(attr smd)
		(fp_rect
			(start -0.925 0.47)
			(end 0.925 -0.47)
			(stroke
				(width 0.05)
				(type default)
			)
			(fill no)
			(layer "B.CrtYd")
		)
		(fp_rect
			(start -0.5 0.25)
			(end 0.5 -0.25)
			(stroke
				(width 0.15)
				(type solid)
			)
			(fill no)
			(layer "B.Fab")
		)
		(fp_text user "${REFERENCE}"
			(at -0.95 -3.168 270)
			(layer "B.Fab")
			(effects
				(font
					(size 0.7 0.7)
					(thickness 0.15)
				)
				(justify left bottom mirror)
			)
		)
		(fp_text user "License: Apache-2.0"
			(at -0.95 -5.169 270)
			(layer "B.Fab")
			(effects
				(font
					(size 0.7 0.7)
					(thickness 0.15)
				)
				(justify left bottom mirror)
			)
		)
		(fp_text user "Author: Antmicro"
			(at -0.95 -4.169 270)
			(layer "B.Fab")
			(effects
				(font
					(size 0.7 0.7)
					(thickness 0.15)
				)
				(justify left bottom mirror)
			)
		)
		(pad "1" smd roundrect
			(at -0.48 0 90)
			(size 0.59 0.64)
			(layers "B.Cu" "B.Mask" "B.Paste")
			(roundrect_rratio 0.25)
			(net 163 "/Supply/DC-DC VCCINT/V_{CC}")
			(pintype "passive")
		)
		(pad "2" smd roundrect
			(at 0.48 0 90)
			(size 0.59 0.64)
			(layers "B.Cu" "B.Mask" "B.Paste")
			(roundrect_rratio 0.25)
			(net 724 "/Supply/DC-DC VCCINT/TAKE0")
			(pintype "passive")
		)
	)
	(footprint "antmicro-footprints:R_0402_1005Metric"
		(layer "B.Cu")
		(at 253.039499 139.3)
		(descr "Resistor SMD 0402")
		(tags "resistor SMD 0402")
		(property "Reference" "R190"
			(at -4.089499 0.4 0)
			(layer "B.SilkS")
			(effects
				(font
					(size 0.7 0.7)
					(thickness 0.15)
				)
				(justify right bottom mirror)
			)
		)
		(property "Value" "R_47k_0402"
			(at -1.011843 -1.772047 0)
			(layer "B.Fab")
			(effects
				(font
					(size 0.7 0.7)
					(thickness 0.15)
				)
				(justify right bottom mirror)
			)
		)
		(property "Datasheet" "https://www.bourns.com/docs/product-datasheets/cr.pdf"
			(at 0 0 0)
			(layer "F.Fab")
			(hide yes)
			(effects
				(font
					(size 1.27 1.27)
					(thickness 0.15)
				)
			)
		)
		(property "Manufacturer" "Bourns"
			(at 0 0 0)
			(unlocked yes)
			(layer "B.Fab")
			(hide yes)
			(effects
				(font
					(size 1 1)
					(thickness 0.15)
				)
				(justify mirror)
			)
		)
		(property "MPN" "CR0402-FX-4702GLF"
			(at 0 0 0)
			(unlocked yes)
			(layer "B.Fab")
			(hide yes)
			(effects
				(font
					(size 1 1)
					(thickness 0.15)
				)
				(justify mirror)
			)
		)
		(property "Val" "47k"
			(at 0 0 0)
			(unlocked yes)
			(layer "B.Fab")
			(hide yes)
			(effects
				(font
					(size 1 1)
					(thickness 0.15)
				)
				(justify mirror)
			)
		)
		(property "License" "Apache-2.0"
			(at 0 0 0)
			(unlocked yes)
			(layer "B.Fab")
			(hide yes)
			(effects
				(font
					(size 1 1)
					(thickness 0.15)
				)
				(justify mirror)
			)
		)
		(property "Author" "Antmicro"
			(at 0 0 0)
			(unlocked yes)
			(layer "B.Fab")
			(hide yes)
			(effects
				(font
					(size 1 1)
					(thickness 0.15)
				)
				(justify mirror)
			)
		)
		(property "Tolerance" "1%"
			(at 0 0 0)
			(unlocked yes)
			(layer "B.Fab")
			(hide yes)
			(effects
				(font
					(size 1 1)
					(thickness 0.15)
				)
				(justify mirror)
			)
		)
		(sheetname "/Supply/")
		(sheetfile "supply.kicad_sch")
		(attr smd)
		(fp_rect
			(start -0.925 0.47)
			(end 0.925 -0.47)
			(stroke
				(width 0.05)
				(type default)
			)
			(fill no)
			(layer "B.CrtYd")
		)
		(fp_rect
			(start -0.5 0.25)
			(end 0.5 -0.25)
			(stroke
				(width 0.15)
				(type solid)
			)
			(fill no)
			(layer "B.Fab")
		)
		(fp_text user "Author: Antmicro"
			(at -0.95 -4.169 180)
			(layer "B.Fab")
			(effects
				(font
					(size 0.7 0.7)
					(thickness 0.15)
				)
				(justify left bottom mirror)
			)
		)
		(fp_text user "License: Apache-2.0"
			(at -0.95 -5.169 180)
			(layer "B.Fab")
			(effects
				(font
					(size 0.7 0.7)
					(thickness 0.15)
				)
				(justify left bottom mirror)
			)
		)
		(fp_text user "${REFERENCE}"
			(at -0.95 -3.168 180)
			(layer "B.Fab")
			(effects
				(font
					(size 0.7 0.7)
					(thickness 0.15)
				)
				(justify left bottom mirror)
			)
		)
		(pad "1" smd roundrect
			(at -0.48 0)
			(size 0.59 0.64)
			(layers "B.Cu" "B.Mask" "B.Paste")
			(roundrect_rratio 0.25)
			(net 170 "/Supply/EN3")
			(pintype "passive")
		)
		(pad "2" smd roundrect
			(at 0.48 0)
			(size 0.59 0.64)
			(layers "B.Cu" "B.Mask" "B.Paste")
			(roundrect_rratio 0.25)
			(net 38 "+3V3_AON")
			(pintype "passive")
		)
	)
	(footprint "antmicro-footprints:R_0402_1005Metric"
		(layer "B.Cu")
		(at 222.385 181.21)
		(descr "Resistor SMD 0402")
		(tags "resistor SMD 0402")
		(property "Reference" "R202"
			(at -5.06 0.515 0)
			(layer "B.SilkS")
			(effects
				(font
					(size 0.7 0.7)
					(thickness 0.15)
				)
				(justify right bottom mirror)
			)
		)
		(property "Value" "R_8k16_0402"
			(at -1.011843 -1.772047 0)
			(layer "B.Fab")
			(effects
				(font
					(size 0.7 0.7)
					(thickness 0.15)
				)
				(justify right bottom mirror)
			)
		)
		(property "Datasheet" "https://www.yageo.com/upload/media/product/app/datasheet/rchip/pyu-rt_1-to-0.01_rohs_l.pdf"
			(at 0 0 0)
			(layer "F.Fab")
			(hide yes)
			(effects
				(font
					(size 1.27 1.27)
					(thickness 0.15)
				)
			)
		)
		(property "MPN" "RT0402BRE078K16L"
			(at 0 0 0)
			(unlocked yes)
			(layer "B.Fab")
			(hide yes)
			(effects
				(font
					(size 1 1)
					(thickness 0.15)
				)
				(justify mirror)
			)
		)
		(property "Manufacturer" "YAGEO"
			(at 0 0 0)
			(unlocked yes)
			(layer "B.Fab")
			(hide yes)
			(effects
				(font
					(size 1 1)
					(thickness 0.15)
				)
				(justify mirror)
			)
		)
		(property "License" "Apache-2.0"
			(at 0 0 0)
			(unlocked yes)
			(layer "B.Fab")
			(hide yes)
			(effects
				(font
					(size 1 1)
					(thickness 0.15)
				)
				(justify mirror)
			)
		)
		(property "Author" "Antmicro"
			(at 0 0 0)
			(unlocked yes)
			(layer "B.Fab")
			(hide yes)
			(effects
				(font
					(size 1 1)
					(thickness 0.15)
				)
				(justify mirror)
			)
		)
		(property "Val" "8k16"
			(at 0 0 0)
			(unlocked yes)
			(layer "B.Fab")
			(hide yes)
			(effects
				(font
					(size 1 1)
					(thickness 0.15)
				)
				(justify mirror)
			)
		)
		(property "Tolerance" "0.1%"
			(at 0 0 0)
			(unlocked yes)
			(layer "B.Fab")
			(hide yes)
			(effects
				(font
					(size 1 1)
					(thickness 0.15)
				)
				(justify mirror)
			)
		)
		(sheetname "/Supply/DC-DC VCCINT/")
		(sheetfile "dc-dc-vccint.kicad_sch")
		(attr smd)
		(fp_rect
			(start -0.925 0.47)
			(end 0.925 -0.47)
			(stroke
				(width 0.05)
				(type default)
			)
			(fill no)
			(layer "B.CrtYd")
		)
		(fp_rect
			(start -0.5 0.25)
			(end 0.5 -0.25)
			(stroke
				(width 0.15)
				(type solid)
			)
			(fill no)
			(layer "B.Fab")
		)
		(fp_text user "${REFERENCE}"
			(at -0.95 -3.168 180)
			(layer "B.Fab")
			(effects
				(font
					(size 0.7 0.7)
					(thickness 0.15)
				)
				(justify left bottom mirror)
			)
		)
		(fp_text user "Author: Antmicro"
			(at -0.95 -4.169 180)
			(layer "B.Fab")
			(effects
				(font
					(size 0.7 0.7)
					(thickness 0.15)
				)
				(justify left bottom mirror)
			)
		)
		(fp_text user "License: Apache-2.0"
			(at -0.95 -5.169 180)
			(layer "B.Fab")
			(effects
				(font
					(size 0.7 0.7)
					(thickness 0.15)
				)
				(justify left bottom mirror)
			)
		)
		(pad "1" smd roundrect
			(at -0.48 0)
			(size 0.59 0.64)
			(layers "B.Cu" "B.Mask" "B.Paste")
			(roundrect_rratio 0.25)
			(net 755 "/Supply/DC-DC VCCINT/VREF-")
			(pintype "passive")
		)
		(pad "2" smd roundrect
			(at 0.48 0)
			(size 0.59 0.64)
			(layers "B.Cu" "B.Mask" "B.Paste")
			(roundrect_rratio 0.25)
			(net 226 "/Supply/DC-DC VCCINT/V_{0SNS+}")
			(pintype "passive")
		)
	)
	(footprint "antmicro-footprints:C_0402_1005Metric"
		(layer "B.Cu")
		(at 184.510001 167.45 90)
		(descr "Capacitor SMD 0402")
		(tags "capacitor SMD 0402")
		(property "Reference" "C279"
			(at -4 0.401999 90)
			(layer "B.SilkS")
			(effects
				(font
					(size 0.7 0.7)
					(thickness 0.15)
				)
				(justify right bottom mirror)
			)
		)
		(property "Value" "C_100n_0402"
			(at -1.022927 -2.155213 90)
			(layer "B.Fab")
			(effects
				(font
					(size 0.7 0.7)
					(thickness 0.15)
				)
				(justify right bottom mirror)
			)
		)
		(property "Datasheet" "https://www.murata.com/products/productdetail?partno=GRM155R61H104KE14%23"
			(at 0 0 90)
			(layer "F.Fab")
			(hide yes)
			(effects
				(font
					(size 1.27 1.27)
					(thickness 0.15)
				)
			)
		)
		(property "Manufacturer" "Murata"
			(at 0 0 90)
			(unlocked yes)
			(layer "B.Fab")
			(hide yes)
			(effects
				(font
					(size 1 1)
					(thickness 0.15)
				)
				(justify mirror)
			)
		)
		(property "MPN" "GRM155R61H104KE14D"
			(at 0 0 90)
			(unlocked yes)
			(layer "B.Fab")
			(hide yes)
			(effects
				(font
					(size 1 1)
					(thickness 0.15)
				)
				(justify mirror)
			)
		)
		(property "Val" "100n"
			(at 0 0 90)
			(unlocked yes)
			(layer "B.Fab")
			(hide yes)
			(effects
				(font
					(size 1 1)
					(thickness 0.15)
				)
				(justify mirror)
			)
		)
		(property "License" "Apache-2.0"
			(at 0 0 90)
			(unlocked yes)
			(layer "B.Fab")
			(hide yes)
			(effects
				(font
					(size 1 1)
					(thickness 0.15)
				)
				(justify mirror)
			)
		)
		(property "Author" "Antmicro"
			(at 0 0 90)
			(unlocked yes)
			(layer "B.Fab")
			(hide yes)
			(effects
				(font
					(size 1 1)
					(thickness 0.15)
				)
				(justify mirror)
			)
		)
		(property "Voltage" "50V"
			(at 0 0 90)
			(unlocked yes)
			(layer "B.Fab")
			(hide yes)
			(effects
				(font
					(size 1 1)
					(thickness 0.15)
				)
				(justify mirror)
			)
		)
		(property "Dielectric" "X5R"
			(at 0 0 90)
			(unlocked yes)
			(layer "B.Fab")
			(hide yes)
			(effects
				(font
					(size 1 1)
					(thickness 0.15)
				)
				(justify mirror)
			)
		)
		(sheetname "/FPGA MGT Interface/")
		(sheetfile "fpga-mgt.kicad_sch")
		(attr smd)
		(fp_rect
			(start -0.925 0.47)
			(end 0.925 -0.47)
			(stroke
				(width 0.05)
				(type default)
			)
			(fill no)
			(layer "B.CrtYd")
		)
		(fp_line
			(start 0.504 -0.248)
			(end -0.494 -0.248)
			(stroke
				(width 0.15)
				(type solid)
			)
			(layer "B.Fab")
		)
		(fp_line
			(start -0.494 -0.248)
			(end -0.494 0.25)
			(stroke
				(width 0.15)
				(type solid)
			)
			(layer "B.Fab")
		)
		(fp_line
			(start 0.504 0.25)
			(end 0.504 -0.248)
			(stroke
				(width 0.15)
				(type solid)
			)
			(layer "B.Fab")
		)
		(fp_line
			(start -0.494 0.25)
			(end 0.504 0.25)
			(stroke
				(width 0.15)
				(type solid)
			)
			(layer "B.Fab")
		)
		(fp_text user "${REFERENCE}"
			(at -0.939 -4.599 270)
			(layer "B.Fab")
			(effects
				(font
					(size 0.7 0.7)
					(thickness 0.15)
				)
				(justify left bottom mirror)
			)
		)
		(fp_text user "Author: Antmicro"
			(at -0.939 -3.399 270)
			(layer "B.Fab")
			(effects
				(font
					(size 0.7 0.7)
					(thickness 0.15)
				)
				(justify left bottom mirror)
			)
		)
		(fp_text user "License: Apache-2.0"
			(at -0.939 -5.799 270)
			(layer "B.Fab")
			(effects
				(font
					(size 0.7 0.7)
					(thickness 0.15)
				)
				(justify left bottom mirror)
			)
		)
		(pad "1" smd roundrect
			(at -0.48 0 90)
			(size 0.59 0.64)
			(layers "B.Cu" "B.Mask" "B.Paste")
			(roundrect_rratio 0.25)
			(net 267 "/FPGA MGT Interface/HDMI_OUT.D1_P")
			(pintype "passive")
		)
		(pad "2" smd roundrect
			(at 0.48 0 90)
			(size 0.59 0.64)
			(layers "B.Cu" "B.Mask" "B.Paste")
			(roundrect_rratio 0.25)
			(net 630 "/FPGA MGT Interface/HDMI_FPGA.TX1_P")
			(pintype "passive")
		)
	)
)
